FILE_TYPE=LIBRARY_PARTS;
primitive '9QXL2001BNHGI8';
  pin
    'DIF_IN#':
      PIN_NUMBER='(H1)';
      INPUT_LOAD='(-0.01,0.01)';
    'NC12':
      PIN_NUMBER='(J2)';
      OUTPUT_TYPE='(TS,TS)';
      INPUT_LOAD='(-0.01,0.01)';
      OUTPUT_LOAD='(1.0,-1.0)';
    'NC1':
      PIN_NUMBER='(B3)';
      OUTPUT_TYPE='(TS,TS)';
      INPUT_LOAD='(-0.01,0.01)';
      OUTPUT_LOAD='(1.0,-1.0)';
    'NC10':
      PIN_NUMBER='(G2)';
      OUTPUT_TYPE='(TS,TS)';
      INPUT_LOAD='(-0.01,0.01)';
      OUTPUT_LOAD='(1.0,-1.0)';
    'DIF15':
      PIN_NUMBER='(A5)';
      OUTPUT_LOAD='(1.0,-1.0)';
    'DIF17':
      PIN_NUMBER='(A1)';
      OUTPUT_LOAD='(1.0,-1.0)';
    'DIF18#':
      PIN_NUMBER='(D1)';
      OUTPUT_LOAD='(1.0,-1.0)';
    'VCKPWRGD_PD#':
      PIN_NUMBER='(M6)';
      INPUT_LOAD='(-0.01,0.01)';
    'EPAD':
      PIN_NUMBER='(TH)';
      PINUSE='POWER';
      NO_LOAD_CHECK='Both';
      NO_IO_CHECK='Both';
      NO_ASSERT_CHECK='TRUE';
      NO_DIR_CHECK='TRUE';
      ALLOW_CONNECT='TRUE';
    'NC8':
      PIN_NUMBER='(F2)';
      OUTPUT_TYPE='(TS,TS)';
      INPUT_LOAD='(-0.01,0.01)';
      OUTPUT_LOAD='(1.0,-1.0)';
    'NC11':
      PIN_NUMBER='(G11)';
      OUTPUT_TYPE='(TS,TS)';
      INPUT_LOAD='(-0.01,0.01)';
      OUTPUT_LOAD='(1.0,-1.0)';
    'NC14':
      PIN_NUMBER='(K2)';
      OUTPUT_TYPE='(TS,TS)';
      INPUT_LOAD='(-0.01,0.01)';
      OUTPUT_LOAD='(1.0,-1.0)';
    'NC15':
      PIN_NUMBER='(L6)';
      OUTPUT_TYPE='(TS,TS)';
      INPUT_LOAD='(-0.01,0.01)';
      OUTPUT_LOAD='(1.0,-1.0)';
    'NC13':
      PIN_NUMBER='(J11)';
      OUTPUT_TYPE='(TS,TS)';
      INPUT_LOAD='(-0.01,0.01)';
      OUTPUT_LOAD='(1.0,-1.0)';
    'DIF0':
      PIN_NUMBER='(J1)';
      OUTPUT_LOAD='(1.0,-1.0)';
    'DIF0#':
      PIN_NUMBER='(K1)';
      OUTPUT_LOAD='(1.0,-1.0)';
    'DIF1':
      PIN_NUMBER='(L1)';
      OUTPUT_LOAD='(1.0,-1.0)';
    'DIF1#':
      PIN_NUMBER='(M1)';
      OUTPUT_LOAD='(1.0,-1.0)';
    'DIF10':
      PIN_NUMBER='(D12)';
      OUTPUT_LOAD='(1.0,-1.0)';
    'DIF10#':
      PIN_NUMBER='(C12)';
      OUTPUT_LOAD='(1.0,-1.0)';
    'DIF11':
      PIN_NUMBER='(B12)';
      OUTPUT_LOAD='(1.0,-1.0)';
    'DIF12#':
      PIN_NUMBER='(A10)';
      OUTPUT_LOAD='(1.0,-1.0)';
    'DIF12':
      PIN_NUMBER='(A11)';
      OUTPUT_LOAD='(1.0,-1.0)';
    'DIF13#':
      PIN_NUMBER='(A8)';
      OUTPUT_LOAD='(1.0,-1.0)';
    'DIF14':
      PIN_NUMBER='(A7)';
      OUTPUT_LOAD='(1.0,-1.0)';
    'DIF14#':
      PIN_NUMBER='(A6)';
      OUTPUT_LOAD='(1.0,-1.0)';
    'DIF15#':
      PIN_NUMBER='(A4)';
      OUTPUT_LOAD='(1.0,-1.0)';
    'DIF16':
      PIN_NUMBER='(A3)';
      OUTPUT_LOAD='(1.0,-1.0)';
    'DIF16#':
      PIN_NUMBER='(A2)';
      OUTPUT_LOAD='(1.0,-1.0)';
    'DIF18':
      PIN_NUMBER='(C1)';
      OUTPUT_LOAD='(1.0,-1.0)';
    'DIF_IN':
      PIN_NUMBER='(G1)';
      INPUT_LOAD='(-0.01,0.01)';
    'DIF11#':
      PIN_NUMBER='(A12)';
      OUTPUT_LOAD='(1.0,-1.0)';
    'DIF13':
      PIN_NUMBER='(A9)';
      OUTPUT_LOAD='(1.0,-1.0)';
    'DIF17#':
      PIN_NUMBER='(B1)';
      OUTPUT_LOAD='(1.0,-1.0)';
    'NC9':
      PIN_NUMBER='(F11)';
      OUTPUT_TYPE='(TS,TS)';
      INPUT_LOAD='(-0.01,0.01)';
      OUTPUT_LOAD='(1.0,-1.0)';
    'NC7':
      PIN_NUMBER='(D11)';
      OUTPUT_TYPE='(TS,TS)';
      INPUT_LOAD='(-0.01,0.01)';
      OUTPUT_LOAD='(1.0,-1.0)';
    'NC16':
      PIN_NUMBER='(L7)';
      OUTPUT_TYPE='(TS,TS)';
      INPUT_LOAD='(-0.01,0.01)';
      OUTPUT_LOAD='(1.0,-1.0)';
    'NC17':
      PIN_NUMBER='(L3)';
      OUTPUT_TYPE='(TS,TS)';
      INPUT_LOAD='(-0.01,0.01)';
      OUTPUT_LOAD='(1.0,-1.0)';
    'NC18':
      PIN_NUMBER='(L9)';
      OUTPUT_TYPE='(TS,TS)';
      INPUT_LOAD='(-0.01,0.01)';
      OUTPUT_LOAD='(1.0,-1.0)';
    'NC2':
      PIN_NUMBER='(B5)';
      OUTPUT_TYPE='(TS,TS)';
      INPUT_LOAD='(-0.01,0.01)';
      OUTPUT_LOAD='(1.0,-1.0)';
    'NC3':
      PIN_NUMBER='(B7)';
      OUTPUT_TYPE='(TS,TS)';
      INPUT_LOAD='(-0.01,0.01)';
      OUTPUT_LOAD='(1.0,-1.0)';
    'NC4':
      PIN_NUMBER='(B9)';
      OUTPUT_TYPE='(TS,TS)';
      INPUT_LOAD='(-0.01,0.01)';
      OUTPUT_LOAD='(1.0,-1.0)';
    'NC5':
      PIN_NUMBER='(C2)';
      OUTPUT_TYPE='(TS,TS)';
      INPUT_LOAD='(-0.01,0.01)';
      OUTPUT_LOAD='(1.0,-1.0)';
    'NC6':
      PIN_NUMBER='(D2)';
      OUTPUT_TYPE='(TS,TS)';
      INPUT_LOAD='(-0.01,0.01)';
      OUTPUT_LOAD='(1.0,-1.0)';
    'DIF2':
      PIN_NUMBER='(M2)';
      OUTPUT_LOAD='(1.0,-1.0)';
    'DIF2#':
      PIN_NUMBER='(M3)';
      OUTPUT_LOAD='(1.0,-1.0)';
    'DIF3':
      PIN_NUMBER='(M4)';
      OUTPUT_LOAD='(1.0,-1.0)';
    'DIF3#':
      PIN_NUMBER='(M5)';
      OUTPUT_LOAD='(1.0,-1.0)';
    'DIF4':
      PIN_NUMBER='(M7)';
      OUTPUT_LOAD='(1.0,-1.0)';
    'DIF4#':
      PIN_NUMBER='(M8)';
      OUTPUT_LOAD='(1.0,-1.0)';
    'DIF5':
      PIN_NUMBER='(M9)';
      OUTPUT_LOAD='(1.0,-1.0)';
    'DIF5#':
      PIN_NUMBER='(M10)';
      OUTPUT_LOAD='(1.0,-1.0)';
    'DIF6':
      PIN_NUMBER='(M11)';
      OUTPUT_LOAD='(1.0,-1.0)';
    'DIF6#':
      PIN_NUMBER='(M12)';
      OUTPUT_LOAD='(1.0,-1.0)';
    'DIF7':
      PIN_NUMBER='(L12)';
      OUTPUT_LOAD='(1.0,-1.0)';
    'DIF7#':
      PIN_NUMBER='(K12)';
      OUTPUT_LOAD='(1.0,-1.0)';
    'DIF8':
      PIN_NUMBER='(J12)';
      OUTPUT_LOAD='(1.0,-1.0)';
    'DIF8#':
      PIN_NUMBER='(H12)';
      OUTPUT_LOAD='(1.0,-1.0)';
    'DIF9':
      PIN_NUMBER='(G12)';
      OUTPUT_LOAD='(1.0,-1.0)';
    'DIF9#':
      PIN_NUMBER='(F12)';
      OUTPUT_LOAD='(1.0,-1.0)';
    'VSBEN':
      PIN_NUMBER='(E2)';
      INPUT_LOAD='(-0.01,0.01)';
    'VOE5#||DATA':
      PIN_NUMBER='(L8)';
      INPUT_LOAD='(-0.01,0.01)';
    'VOE6#||CLK':
      PIN_NUMBER='(L10)';
      INPUT_LOAD='(-0.01,0.01)';
    'VOE7#':
      PIN_NUMBER='(K11)';
      INPUT_LOAD='(-0.01,0.01)';
    'VOE8#':
      PIN_NUMBER='(H11)';
      INPUT_LOAD='(-0.01,0.01)';
    'VOE9#':
      PIN_NUMBER='(E12)';
      INPUT_LOAD='(-0.01,0.01)';
    'VOE10#||SHFT_LD#':
      PIN_NUMBER='(E11)';
      INPUT_LOAD='(-0.01,0.01)';
    'VOE11#':
      PIN_NUMBER='(C11)';
      INPUT_LOAD='(-0.01,0.01)';
    'VOE12#':
      PIN_NUMBER='(B10)';
      INPUT_LOAD='(-0.01,0.01)';
    'SMBCLK':
      PIN_NUMBER='(L5)';
      INPUT_LOAD='(-0.01,0.01)';
    'SMBDAT':
      PIN_NUMBER='(L4)';
      BIDIRECTIONAL='TRUE';
      INPUT_LOAD='(-0.01,0.01)';
      OUTPUT_LOAD='(1.0,-1.0)';
    'VDDA3.3':
      PIN_NUMBER='(B6)';
      PINUSE='POWER';
      NO_LOAD_CHECK='Both';
      NO_IO_CHECK='Both';
      NO_ASSERT_CHECK='TRUE';
      NO_DIR_CHECK='TRUE';
      ALLOW_CONNECT='TRUE';
    'VDDO3.3_B2':
      PIN_NUMBER='(B2)';
      PINUSE='POWER';
      NO_LOAD_CHECK='Both';
      NO_IO_CHECK='Both';
      NO_ASSERT_CHECK='TRUE';
      NO_DIR_CHECK='TRUE';
      ALLOW_CONNECT='TRUE';
    'VDDO3.3_B11':
      PIN_NUMBER='(B11)';
      PINUSE='POWER';
      NO_LOAD_CHECK='Both';
      NO_IO_CHECK='Both';
      NO_ASSERT_CHECK='TRUE';
      NO_DIR_CHECK='TRUE';
      ALLOW_CONNECT='TRUE';
    'VDDO3.3_L2':
      PIN_NUMBER='(L2)';
      PINUSE='POWER';
      NO_LOAD_CHECK='Both';
      NO_IO_CHECK='Both';
      NO_ASSERT_CHECK='TRUE';
      NO_DIR_CHECK='TRUE';
      ALLOW_CONNECT='TRUE';
    'VDDO3.3_L11':
      PIN_NUMBER='(L11)';
      PINUSE='POWER';
      NO_LOAD_CHECK='Both';
      NO_IO_CHECK='Both';
      NO_ASSERT_CHECK='TRUE';
      NO_DIR_CHECK='TRUE';
      ALLOW_CONNECT='TRUE';
    'VDDR3.3':
      PIN_NUMBER='(H2)';
      PINUSE='POWER';
      NO_LOAD_CHECK='Both';
      NO_IO_CHECK='Both';
      NO_ASSERT_CHECK='TRUE';
      NO_DIR_CHECK='TRUE';
      ALLOW_CONNECT='TRUE';
    '^VSADR0_TRI':
      PIN_NUMBER='(B4)';
      INPUT_LOAD='(-0.01,0.01)';
    '^VSADR1_TRI':
      PIN_NUMBER='(B8)';
      INPUT_LOAD='(-0.01,0.01)';
    'DIF19':
      PIN_NUMBER='(E1)';
      OUTPUT_LOAD='(1.0,-1.0)';
    'DIF19#':
      PIN_NUMBER='(F1)';
      OUTPUT_LOAD='(1.0,-1.0)';
  end_pin;
  body
    PART_NAME='9QXL2001BNHGI8';
    BODY_NAME='9QXL2001BNHGI8';
    PHYS_DES_PREFIX='U';
    CLASS='IC';
  end_body;
end_primitive;

END.
